# BASEBOARD_FAB2 (Tioga Pass) — schematic parts with pin connectivity, parts 2402–2402 of 4751; source: Cadence DE-HDL packaged netlist (pstxprt.dat, pstxnet.dat, pstchip.dat)

J9T1  SCONN288_H44441003  SCONN  pkg PIP  page 78
  1  \12v\(1)  = P12V_NVDIMM_GHJ
  2  VSS(93)  GROUND  = GND
  3  DQ(4)  BI  = M_G_DQ<4>
  4  VSS(92)  GROUND  = GND
  5  DQ(0)  BI  = M_G_DQ<0>
  6  VSS(91)  GROUND  = GND
  7  DQS9P  BI  = M_G_DQS_DP<9>
  8  DQS9N  BI  = M_G_DQS_DN<9>
  9  VSS(90)  GROUND  = GND
  10  DQ(6)  BI  = M_G_DQ<6>
  11  VSS(89)  GROUND  = GND
  12  DQ(2)  BI  = M_G_DQ<2>
  13  VSS(88)  GROUND  = GND
  14  DQ(12)  BI  = M_G_DQ<12>
  15  VSS(87)  GROUND  = GND
  16  DQ(8)  BI  = M_G_DQ<8>
  17  VSS(86)  GROUND  = GND
  18  DQS10P  BI  = M_G_DQS_DP<10>
  19  DQS10N  BI  = M_G_DQS_DN<10>
  20  VSS(85)  GROUND  = GND
  21  DQ(14)  BI  = M_G_DQ<14>
  22  VSS(84)  GROUND  = GND
  23  DQ(10)  BI  = M_G_DQ<10>
  24  VSS(83)  GROUND  = GND
  25  DQ(20)  BI  = M_G_DQ<20>
  26  VSS(82)  GROUND  = GND
  27  DQ(16)  BI  = M_G_DQ<16>
  28  VSS(81)  GROUND  = GND
  29  DQS11P  BI  = M_G_DQS_DP<11>
  30  DQS11N  BI  = M_G_DQS_DN<11>
  31  VSS(80)  GROUND  = GND
  32  DQ(22)  BI  = M_G_DQ<22>
  33  VSS(79)  GROUND  = GND
  34  DQ(18)  BI  = M_G_DQ<18>
  35  VSS(78)  GROUND  = GND
  36  DQ(28)  BI  = M_G_DQ<28>
  37  VSS(77)  GROUND  = GND
  38  DQ(24)  BI  = M_G_DQ<24>
  39  VSS(76)  GROUND  = GND
  40  DQS12P  BI  = M_G_DQS_DP<12>
  41  DQS12N  BI  = M_G_DQS_DN<12>
  42  VSS(75)  GROUND  = GND
  43  DQ(30)  BI  = M_G_DQ<30>
  44  VSS(74)  GROUND  = GND
  45  DQ(26)  BI  = M_G_DQ<26>
  46  VSS(73)  GROUND  = GND
  47  CB(4)  BI  = M_G_ECC<4>
  48  VSS(72)  GROUND  = GND
  49  CB(0)  BI  = M_G_ECC<0>
  50  VSS(71)  GROUND  = GND
  51  DQS17P  BI  = M_G_DQS_DP<17>
  52  DQS17N  BI  = M_G_DQS_DN<17>
  53  VSS(70)  GROUND  = GND
  54  CB(6)  BI  = M_G_ECC<6>
  55  VSS(69)  GROUND  = GND
  56  CB(2)  BI  = M_G_ECC<2>
  57  VSS(68)  GROUND  = GND
  58  RESET_N  BI  = M_GHJ_RST_N
  59  VDD(25)  POWER  = PVDDQ_GHJ
  60  CKE(0)  BI  = M_G_CKE<2>
  61  VDD(24)  POWER  = PVDDQ_GHJ
  62  ACT_N  BI  = M_G_ACT_N
  63  BG(0)  BI  = M_G_BG<0>
  64  VDD(23)  POWER  = PVDDQ_GHJ
  65  A12  BI  = M_G_MA<12>
  66  A9  BI  = M_G_MA<9>
  67  VDD(22)  POWER  = PVDDQ_GHJ
  68  A8  BI  = M_G_MA<8>
  69  A6  BI  = M_G_MA<6>
  70  VDD(21)  POWER  = PVDDQ_GHJ
  71  A3  BI  = M_G_MA<3>
  72  A1  BI  = M_G_MA<1>
  73  VDD(20)  POWER  = PVDDQ_GHJ
  74  CK0P  BI  = M_G_CLK_DP<2>
  75  CK0N  BI  = M_G_CLK_DN<2>
  76  VDD(19)  POWER  = PVDDQ_GHJ
  77  VTT(1)  POWER  = PVTT_GHJ
  78  EVENT_N  BI  = FM_DIMM_EVENT_COD_N
  79  A0  BI  = M_G_MA<0>
  80  VDD(18)  POWER  = PVDDQ_GHJ
  81  BA(0)  BI  = M_G_BA<0>
  82  A16_RAS_N  BI  = M_G_MA<16>
  83  VDD(17)  POWER  = PVDDQ_GHJ
  84  S0_N  BI  = M_G_CS_N<4>
  85  VDD(16)  POWER  = PVDDQ_GHJ
  86  A15_CAS_N  BI  = M_G_MA<15>
  87  ODT(0)  BI  = M_G_ODT<2>
  88  VDD(15)  POWER  = PVDDQ_GHJ
  89  S1_N  BI  = M_G_CS_N<5>
  90  VDD(14)  POWER  = PVDDQ_GHJ
  91  ODT(1)  BI  = M_G_ODT<3>
  92  VDD(13)  POWER  = PVDDQ_GHJ
  93  S2_N_C(0)  BI  = M_G_CS_N<6>
  94  VSS(67)  GROUND  = GND
  95  DQ(36)  BI  = M_G_DQ<36>
  96  VSS(66)  GROUND  = GND
  97  DQ(32)  BI  = M_G_DQ<32>
  98  VSS(65)  GROUND  = GND
  99  DQS13P  BI  = M_G_DQS_DP<13>
  100  DQS13N  BI  = M_G_DQS_DN<13>
  101  VSS(64)  GROUND  = GND
  102  DQ(38)  BI  = M_G_DQ<38>
  103  VSS(63)  GROUND  = GND
  104  DQ(34)  BI  = M_G_DQ<34>
  105  VSS(62)  GROUND  = GND
  106  DQ(44)  BI  = M_G_DQ<44>
  107  VSS(61)  GROUND  = GND
  108  DQ(40)  BI  = M_G_DQ<40>
  109  VSS(60)  GROUND  = GND
  110  DQS14P  BI  = M_G_DQS_DP<14>
  111  DQS14N  BI  = M_G_DQS_DN<14>
  112  VSS(59)  GROUND  = GND
  113  DQ(46)  BI  = M_G_DQ<46>
  114  VSS(58)  GROUND  = GND
  115  DQ(42)  BI  = M_G_DQ<42>
  116  VSS(57)  GROUND  = GND
  117  DQ(52)  BI  = M_G_DQ<52>
  118  VSS(56)  GROUND  = GND
  119  DQ(48)  BI  = M_G_DQ<48>
  120  VSS(55)  GROUND  = GND
  121  DQS15P  BI  = M_G_DQS_DP<15>
  122  DQS15N  BI  = M_G_DQS_DN<15>
  123  VSS(54)  GROUND  = GND
  124  DQ(54)  BI  = M_G_DQ<54>
  125  VSS(53)  GROUND  = GND
  126  DQ(50)  BI  = M_G_DQ<50>
  127  VSS(52)  GROUND  = GND
  128  DQ(60)  BI  = M_G_DQ<60>
  129  VSS(51)  GROUND  = GND
  130  DQ(56)  BI  = M_G_DQ<56>
  131  VSS(50)  GROUND  = GND
  132  DQS16P  BI  = M_G_DQS_DP<16>
  133  DQS16N  BI  = M_G_DQS_DN<16>
  134  VSS(49)  GROUND  = GND
  135  DQ(62)  BI  = M_G_DQ<62>
  136  VSS(48)  GROUND  = GND
  137  DQ(58)  BI  = M_G_DQ<58>
  138  VSS(47)  GROUND  = GND
  139  SA(0)  BI  = PVPP_GHJ
  140  SA(1)  BI  = GND
  141  SCL  BI  = SMB_DDR_GHJ_VPP_SCL
  142  VPP(4)  POWER  = PVPP_GHJ
  143  VPP(3)  POWER  = PVPP_GHJ
  144  RFU(2)  BI  = TP_CH_G_DIMM0_RFU_2
  145  \12v\(0)  = P12V_NVDIMM_GHJ
  146  VREFCA  BI  = M_G_VREF
  147  VSS(46)  GROUND  = GND
  148  DQ(5)  BI  = M_G_DQ<5>
  149  VSS(45)  GROUND  = GND
  150  DQ(1)  BI  = M_G_DQ<1>
  151  VSS(44)  GROUND  = GND
  152  DQS0N  BI  = M_G_DQS_DN<0>
  153  DQS0P  BI  = M_G_DQS_DP<0>
  154  VSS(43)  GROUND  = GND
  155  DQ(7)  BI  = M_G_DQ<7>
  156  VSS(42)  GROUND  = GND
  157  DQ(3)  BI  = M_G_DQ<3>
  158  VSS(41)  GROUND  = GND
  159  DQ(13)  BI  = M_G_DQ<13>
  160  VSS(40)  GROUND  = GND
  161  DQ(9)  BI  = M_G_DQ<9>
  162  VSS(39)  GROUND  = GND
  163  DQS1N  BI  = M_G_DQS_DN<1>
  164  DQS1P  BI  = M_G_DQS_DP<1>
  165  VSS(38)  GROUND  = GND
  166  DQ(15)  BI  = M_G_DQ<15>
  167  VSS(37)  GROUND  = GND
  168  DQ(11)  BI  = M_G_DQ<11>
  169  VSS(36)  GROUND  = GND
  170  DQ(21)  BI  = M_G_DQ<21>
  171  VSS(35)  GROUND  = GND
  172  DQ(17)  BI  = M_G_DQ<17>
  173  VSS(34)  GROUND  = GND
  174  DQS2N  BI  = M_G_DQS_DN<2>
  175  DQS2P  BI  = M_G_DQS_DP<2>
  176  VSS(33)  GROUND  = GND
  177  DQ(23)  BI  = M_G_DQ<23>
  178  VSS(32)  GROUND  = GND
  179  DQ(19)  BI  = M_G_DQ<19>
  180  VSS(31)  GROUND  = GND
  181  DQ(29)  BI  = M_G_DQ<29>
  182  VSS(30)  GROUND  = GND
  183  DQ(25)  BI  = M_G_DQ<25>
  184  VSS(29)  GROUND  = GND
  185  DQS3N  BI  = M_G_DQS_DN<3>
  186  DQS3P  BI  = M_G_DQS_DP<3>
  187  VSS(28)  GROUND  = GND
  188  DQ(31)  BI  = M_G_DQ<31>
  189  VSS(27)  GROUND  = GND
  190  DQ(27)  BI  = M_G_DQ<27>
  191  VSS(26)  GROUND  = GND
  192  CB(5)  BI  = M_G_ECC<5>
  193  VSS(25)  GROUND  = GND
  194  CB(1)  BI  = M_G_ECC<1>
  195  VSS(24)  GROUND  = GND
  196  DQS8N  BI  = M_G_DQS_DN<8>
  197  DQS8P  BI  = M_G_DQS_DP<8>
  198  VSS(23)  GROUND  = GND
  199  CB(7)  BI  = M_G_ECC<7>
  200  VSS(22)  GROUND  = GND
  201  CB(3)  BI  = M_G_ECC<3>
  202  VSS(21)  GROUND  = GND
  203  CKE(1)  BI  = M_G_CKE<3>
  204  VDD(12)  POWER  = PVDDQ_GHJ
  205  RFU(0)  BI  = TP_CH_G_DIMM0_RFU_0
  206  VDD(11)  POWER  = PVDDQ_GHJ
  207  BG(1)  BI  = M_G_BG<1>
  208  ALERT_N  BI  = M_G_ALERT_N
  209  VDD(10)  POWER  = PVDDQ_GHJ
  210  A11  BI  = M_G_MA<11>
  211  A7  BI  = M_G_MA<7>
  212  VDD(9)  POWER  = PVDDQ_GHJ
  213  A5  BI  = M_G_MA<5>
  214  A4  BI  = M_G_MA<4>
  215  VDD(8)  POWER  = PVDDQ_GHJ
  216  A2  BI  = M_G_MA<2>
  217  VDD(7)  POWER  = PVDDQ_GHJ
  218  CK1P  BI  = M_G_CLK_DP<3>
  219  CK1N  BI  = M_G_CLK_DN<3>
  220  VDD(6)  POWER  = PVDDQ_GHJ
  221  VTT(0)  POWER  = PVTT_GHJ
  222  PAR  BI  = M_G_PAR
  223  VDD(5)  POWER  = PVDDQ_GHJ
  224  BA(1)  BI  = M_G_BA<1>
  225  A10  BI  = M_G_MA<10>
  226  VDD(4)  POWER  = PVDDQ_GHJ
  227  RFU(1)  BI  = TP_CH_G_DIMM0_RFU_1
  228  A14_WE_N  BI  = M_G_MA<14>
  229  VDD(3)  POWER  = PVDDQ_GHJ
  230  SAVE_N_NC  BI  = FM_ADR_COMPLETE_GHJ_N
  231  VDD(2)  POWER  = PVDDQ_GHJ
  232  A13  BI  = M_G_MA<13>
  233  VDD(1)  POWER  = PVDDQ_GHJ
  234  A17  BI  = M_G_MA<17>
  235  C(2)  BI  = M_G_C<2>
  236  VDD(0)  POWER  = PVDDQ_GHJ
  237  S3_N_C(1)  BI  = M_G_CS_N<7>
  238  SA(2)  BI  = GND
  239  VSS(20)  GROUND  = GND
  240  DQ(37)  BI  = M_G_DQ<37>
  241  VSS(19)  GROUND  = GND
  242  DQ(33)  BI  = M_G_DQ<33>
  243  VSS(18)  GROUND  = GND
  244  DQS4N  BI  = M_G_DQS_DN<4>
  245  DQS4P  BI  = M_G_DQS_DP<4>
  246  VSS(17)  GROUND  = GND
  247  DQ(39)  BI  = M_G_DQ<39>
  248  VSS(16)  GROUND  = GND
  249  DQ(35)  BI  = M_G_DQ<35>
  250  VSS(15)  GROUND  = GND
  251  DQ(45)  BI  = M_G_DQ<45>
  252  VSS(14)  GROUND  = GND
  253  DQ(41)  BI  = M_G_DQ<41>
  254  VSS(13)  GROUND  = GND
  255  DQS5N  BI  = M_G_DQS_DN<5>
  256  DQS5P  BI  = M_G_DQS_DP<5>
  257  VSS(12)  GROUND  = GND
  258  DQ(47)  BI  = M_G_DQ<47>
  259  VSS(11)  GROUND  = GND
  260  DQ(43)  BI  = M_G_DQ<43>
  261  VSS(10)  GROUND  = GND
  262  DQ(53)  BI  = M_G_DQ<53>
  263  VSS(9)  GROUND  = GND
  264  DQ(49)  BI  = M_G_DQ<49>
  265  VSS(8)  GROUND  = GND
  266  DQS6N  BI  = M_G_DQS_DN<6>
  267  DQS6P  BI  = M_G_DQS_DP<6>
  268  VSS(7)  GROUND  = GND
  269  DQ(55)  BI  = M_G_DQ<55>
  270  VSS(6)  GROUND  = GND
  271  DQ(51)  BI  = M_G_DQ<51>
  272  VSS(5)  GROUND  = GND
  273  DQ(61)  BI  = M_G_DQ<61>
  274  VSS(4)  GROUND  = GND
  275  DQ(57)  BI  = M_G_DQ<57>
  276  VSS(3)  GROUND  = GND
  277  DQS7N  BI  = M_G_DQS_DN<7>
  278  DQS7P  BI  = M_G_DQS_DP<7>
  279  VSS(2)  GROUND  = GND
  280  DQ(63)  BI  = M_G_DQ<63>
  281  VSS(1)  GROUND  = GND
  282  DQ(59)  BI  = M_G_DQ<59>
  283  VSS(0)  GROUND  = GND
  284  VDDSPD  BI  = PVPP_GHJ
  285  SDA  BI  = SMB_DDR_GHJ_VPP_SDA
  286  VPP(1)  POWER  = PVPP_GHJ
  287  VPP(0)  POWER  = PVPP_GHJ
  288  VPP(2)  POWER  = PVPP_GHJ
